(kicad_pcb
	(version 20260206)
	(generator "pcbnew")
	(generator_version "10.0")
	(general
		(thickness 1.6)
		(legacy_teardrops no)
	)
	(paper "A4")
	(title_block
		(title "04192023_DAF0TMB3IC0_F0TG_MB_C_brd_V02_OCP.brd")
		(comment 1 "Grand Teton / footprints 1978-1985 of 8354")
	)
	(layers
		(0 "F.Cu" signal "TOP")
		(4 "In1.Cu" signal "GND")
		(6 "In2.Cu" signal "IN1")
		(8 "In3.Cu" signal "GND1")
		(10 "In4.Cu" signal "IN2")
		(12 "In5.Cu" signal "GND2")
		(14 "In6.Cu" signal "IN3")
		(16 "In7.Cu" signal "GND3")
		(18 "In8.Cu" signal "VCC")
		(20 "In9.Cu" signal "VCC1")
		(22 "In10.Cu" signal "GND4")
		(24 "In11.Cu" signal "IN4")
		(26 "In12.Cu" signal "GND5")
		(28 "In13.Cu" signal "IN5")
		(30 "In14.Cu" signal "GND6")
		(32 "In15.Cu" signal "IN6")
		(34 "In16.Cu" signal "GND7")
		(2 "B.Cu" signal "BOTTOM")
		(9 "F.Adhes" user "F.Adhesive")
		(11 "B.Adhes" user "B.Adhesive")
		(13 "F.Paste" user "Package Geometry/Pastemask Top")
		(15 "B.Paste" user "Package Geometry/Pastemask Bottom")
		(5 "F.SilkS" user "Ref Des/Silkscreen Top")
		(7 "B.SilkS" user "Ref Des/Silkscreen Bottom")
		(1 "F.Mask" user "Board Geometry/Soldermask Top")
		(3 "B.Mask" user "Board Geometry/Soldermask Bottom")
		(17 "Dwgs.User" user "User.Drawings")
		(19 "Cmts.User" user "User.Comments")
		(21 "Eco1.User" user "User.Eco1")
		(23 "Eco2.User" user "User.Eco2")
		(25 "Edge.Cuts" user "Board Geometry/Outline")
		(27 "Margin" user)
		(31 "F.CrtYd" user "Package Geometry/Place Bound Top")
		(29 "B.CrtYd" user "Package Geometry/Place Bound Bottom")
		(35 "F.Fab" user "Ref Des/Assembly Top")
		(33 "B.Fab" user "Ref Des/Assembly Bottom")
	)
	(footprint ""
		(layer "F.Cu")
		(at 447.687192 -21.236178 180)
		(property "Reference" "PR5484"
			(at 0 0 180)
			(layer "F.SilkS")
			(hide yes)
			(effects
				(font
					(size 1.27 1.27)
				)
			)
		)
		(property "Value" ""
			(at 0 0 180)
			(layer "F.Fab")
			(effects
				(font
					(size 1.27 1.27)
				)
			)
		)
		(duplicate_pad_numbers_are_jumpers no)
		(fp_line
			(start 0.7874 0.4064)
			(end -0.7874 0.4064)
			(stroke
				(width 0.1524)
				(type default)
			)
			(layer "F.SilkS")
		)
		(fp_line
			(start 0.7874 -0.4064)
			(end 0.7874 0.4064)
			(stroke
				(width 0.1524)
				(type default)
			)
			(layer "F.SilkS")
		)
		(fp_line
			(start -0.7874 0.4064)
			(end -0.7874 -0.4064)
			(stroke
				(width 0.1524)
				(type default)
			)
			(layer "F.SilkS")
		)
		(fp_line
			(start -0.7874 -0.4064)
			(end 0.7874 -0.4064)
			(stroke
				(width 0.1524)
				(type default)
			)
			(layer "F.SilkS")
		)
		(fp_line
			(start 0.67945 0.3048)
			(end 0.120396 0.3048)
			(stroke
				(width 0.1)
				(type default)
			)
			(layer "F.Fab")
		)
		(fp_line
			(start 0.67945 -0.3048)
			(end 0.67945 0.3048)
			(stroke
				(width 0.1)
				(type default)
			)
			(layer "F.Fab")
		)
		(fp_line
			(start 0.12065 -0.2794)
			(end 0.12065 -0.3048)
			(stroke
				(width 0.1)
				(type default)
			)
			(layer "F.Fab")
		)
		(fp_line
			(start 0.12065 -0.3048)
			(end 0.67945 -0.3048)
			(stroke
				(width 0.1)
				(type default)
			)
			(layer "F.Fab")
		)
		(fp_line
			(start 0.120396 0.3048)
			(end 0.120396 0.2794)
			(stroke
				(width 0.1)
				(type default)
			)
			(layer "F.Fab")
		)
		(fp_line
			(start 0.120396 0.2794)
			(end -0.12065 0.2794)
			(stroke
				(width 0.1)
				(type default)
			)
			(layer "F.Fab")
		)
		(fp_line
			(start -0.12065 0.3048)
			(end -0.67945 0.3048)
			(stroke
				(width 0.1)
				(type default)
			)
			(layer "F.Fab")
		)
		(fp_line
			(start -0.12065 0.2794)
			(end -0.12065 0.3048)
			(stroke
				(width 0.1)
				(type default)
			)
			(layer "F.Fab")
		)
		(fp_line
			(start -0.12065 -0.2794)
			(end 0.12065 -0.2794)
			(stroke
				(width 0.1)
				(type default)
			)
			(layer "F.Fab")
		)
		(fp_line
			(start -0.12065 -0.305054)
			(end -0.12065 -0.2794)
			(stroke
				(width 0.1)
				(type default)
			)
			(layer "F.Fab")
		)
		(fp_line
			(start -0.67945 0.3048)
			(end -0.67945 -0.305054)
			(stroke
				(width 0.1)
				(type default)
			)
			(layer "F.Fab")
		)
		(fp_line
			(start -0.67945 -0.305054)
			(end -0.12065 -0.305054)
			(stroke
				(width 0.1)
				(type default)
			)
			(layer "F.Fab")
		)
		(pad "1" smd circle
			(at -0.40005 0 180)
			(size 0 0)
			(layers "F.Cu" "F.Mask" "F.Paste")
			(net "P12V_OCP_CB_1")
		)
		(pad "2" smd circle
			(at 0.40005 0 180)
			(size 0 0)
			(layers "F.Cu" "F.Mask" "F.Paste")
			(net "GND")
		)
	)
	(footprint ""
		(layer "F.Cu")
		(at 139.065 -116.586 180)
		(property "Reference" "C8022"
			(at 0 0 180)
			(layer "F.SilkS")
			(hide yes)
			(effects
				(font
					(size 1.27 1.27)
				)
			)
		)
		(property "Value" ""
			(at 0 0 180)
			(layer "F.Fab")
			(effects
				(font
					(size 1.27 1.27)
				)
			)
		)
		(duplicate_pad_numbers_are_jumpers no)
		(fp_line
			(start 0.7874 0.4064)
			(end -0.7874 0.4064)
			(stroke
				(width 0.1524)
				(type default)
			)
			(layer "F.SilkS")
		)
		(fp_line
			(start 0.7874 -0.4064)
			(end 0.7874 0.4064)
			(stroke
				(width 0.1524)
				(type default)
			)
			(layer "F.SilkS")
		)
		(fp_line
			(start -0.7874 0.4064)
			(end -0.7874 -0.4064)
			(stroke
				(width 0.1524)
				(type default)
			)
			(layer "F.SilkS")
		)
		(fp_line
			(start -0.7874 -0.4064)
			(end 0.7874 -0.4064)
			(stroke
				(width 0.1524)
				(type default)
			)
			(layer "F.SilkS")
		)
		(fp_line
			(start 0.67945 0.3048)
			(end 0.120396 0.3048)
			(stroke
				(width 0.1)
				(type default)
			)
			(layer "F.Fab")
		)
		(fp_line
			(start 0.67945 -0.3048)
			(end 0.67945 0.3048)
			(stroke
				(width 0.1)
				(type default)
			)
			(layer "F.Fab")
		)
		(fp_line
			(start 0.12065 -0.2794)
			(end 0.12065 -0.3048)
			(stroke
				(width 0.1)
				(type default)
			)
			(layer "F.Fab")
		)
		(fp_line
			(start 0.12065 -0.3048)
			(end 0.67945 -0.3048)
			(stroke
				(width 0.1)
				(type default)
			)
			(layer "F.Fab")
		)
		(fp_line
			(start 0.120396 0.3048)
			(end 0.120396 0.2794)
			(stroke
				(width 0.1)
				(type default)
			)
			(layer "F.Fab")
		)
		(fp_line
			(start 0.120396 0.2794)
			(end -0.12065 0.2794)
			(stroke
				(width 0.1)
				(type default)
			)
			(layer "F.Fab")
		)
		(fp_line
			(start -0.12065 0.3048)
			(end -0.67945 0.3048)
			(stroke
				(width 0.1)
				(type default)
			)
			(layer "F.Fab")
		)
		(fp_line
			(start -0.12065 0.2794)
			(end -0.12065 0.3048)
			(stroke
				(width 0.1)
				(type default)
			)
			(layer "F.Fab")
		)
		(fp_line
			(start -0.12065 -0.2794)
			(end 0.12065 -0.2794)
			(stroke
				(width 0.1)
				(type default)
			)
			(layer "F.Fab")
		)
		(fp_line
			(start -0.12065 -0.305054)
			(end -0.12065 -0.2794)
			(stroke
				(width 0.1)
				(type default)
			)
			(layer "F.Fab")
		)
		(fp_line
			(start -0.67945 0.3048)
			(end -0.67945 -0.305054)
			(stroke
				(width 0.1)
				(type default)
			)
			(layer "F.Fab")
		)
		(fp_line
			(start -0.67945 -0.305054)
			(end -0.12065 -0.305054)
			(stroke
				(width 0.1)
				(type default)
			)
			(layer "F.Fab")
		)
		(pad "1" smd circle
			(at -0.40005 0 180)
			(size 0 0)
			(layers "F.Cu" "F.Mask" "F.Paste")
			(net "P12V_AUX")
		)
		(pad "2" smd circle
			(at 0.40005 0 180)
			(size 0 0)
			(layers "F.Cu" "F.Mask" "F.Paste")
			(net "GND")
		)
	)
	(footprint ""
		(layer "F.Cu")
		(at 44.069 -435.61)
		(property "Reference" "R3506"
			(at 0 0 0)
			(layer "F.SilkS")
			(hide yes)
			(effects
				(font
					(size 1.27 1.27)
				)
			)
		)
		(property "Value" ""
			(at 0 0 0)
			(layer "F.Fab")
			(effects
				(font
					(size 1.27 1.27)
				)
			)
		)
		(duplicate_pad_numbers_are_jumpers no)
		(fp_line
			(start -0.7874 -0.4064)
			(end 0.7874 -0.4064)
			(stroke
				(width 0.1524)
				(type default)
			)
			(layer "F.SilkS")
		)
		(fp_line
			(start -0.7874 0.4064)
			(end -0.7874 -0.4064)
			(stroke
				(width 0.1524)
				(type default)
			)
			(layer "F.SilkS")
		)
		(fp_line
			(start 0.7874 -0.4064)
			(end 0.7874 0.4064)
			(stroke
				(width 0.1524)
				(type default)
			)
			(layer "F.SilkS")
		)
		(fp_line
			(start 0.7874 0.4064)
			(end -0.7874 0.4064)
			(stroke
				(width 0.1524)
				(type default)
			)
			(layer "F.SilkS")
		)
		(fp_line
			(start -0.67945 -0.305054)
			(end -0.12065 -0.305054)
			(stroke
				(width 0.1)
				(type default)
			)
			(layer "F.Fab")
		)
		(fp_line
			(start -0.67945 0.3048)
			(end -0.67945 -0.305054)
			(stroke
				(width 0.1)
				(type default)
			)
			(layer "F.Fab")
		)
		(fp_line
			(start -0.12065 -0.305054)
			(end -0.12065 -0.2794)
			(stroke
				(width 0.1)
				(type default)
			)
			(layer "F.Fab")
		)
		(fp_line
			(start -0.12065 -0.2794)
			(end 0.12065 -0.2794)
			(stroke
				(width 0.1)
				(type default)
			)
			(layer "F.Fab")
		)
		(fp_line
			(start -0.12065 0.2794)
			(end -0.12065 0.3048)
			(stroke
				(width 0.1)
				(type default)
			)
			(layer "F.Fab")
		)
		(fp_line
			(start -0.12065 0.3048)
			(end -0.67945 0.3048)
			(stroke
				(width 0.1)
				(type default)
			)
			(layer "F.Fab")
		)
		(fp_line
			(start 0.120396 0.2794)
			(end -0.12065 0.2794)
			(stroke
				(width 0.1)
				(type default)
			)
			(layer "F.Fab")
		)
		(fp_line
			(start 0.120396 0.3048)
			(end 0.120396 0.2794)
			(stroke
				(width 0.1)
				(type default)
			)
			(layer "F.Fab")
		)
		(fp_line
			(start 0.12065 -0.3048)
			(end 0.67945 -0.3048)
			(stroke
				(width 0.1)
				(type default)
			)
			(layer "F.Fab")
		)
		(fp_line
			(start 0.12065 -0.2794)
			(end 0.12065 -0.3048)
			(stroke
				(width 0.1)
				(type default)
			)
			(layer "F.Fab")
		)
		(fp_line
			(start 0.67945 -0.3048)
			(end 0.67945 0.3048)
			(stroke
				(width 0.1)
				(type default)
			)
			(layer "F.Fab")
		)
		(fp_line
			(start 0.67945 0.3048)
			(end 0.120396 0.3048)
			(stroke
				(width 0.1)
				(type default)
			)
			(layer "F.Fab")
		)
		(pad "1" smd circle
			(at -0.40005 0)
			(size 0 0)
			(layers "F.Cu" "F.Mask" "F.Paste")
			(net "P3V3_AUX")
		)
		(pad "2" smd circle
			(at 0.40005 0)
			(size 0 0)
			(layers "F.Cu" "F.Mask" "F.Paste")
			(net "GPU_FPGA_RST_R_N")
		)
	)
	(footprint ""
		(layer "F.Cu")
		(at 172.540422 -416.484816)
		(property "Reference" "R9009"
			(at 0 0 0)
			(layer "F.SilkS")
			(hide yes)
			(effects
				(font
					(size 1.27 1.27)
				)
			)
		)
		(property "Value" ""
			(at 0 0 0)
			(layer "F.Fab")
			(effects
				(font
					(size 1.27 1.27)
				)
			)
		)
		(duplicate_pad_numbers_are_jumpers no)
		(fp_line
			(start -0.7874 -0.4064)
			(end 0.7874 -0.4064)
			(stroke
				(width 0.1524)
				(type default)
			)
			(layer "F.SilkS")
		)
		(fp_line
			(start -0.7874 0.4064)
			(end -0.7874 -0.4064)
			(stroke
				(width 0.1524)
				(type default)
			)
			(layer "F.SilkS")
		)
		(fp_line
			(start 0.7874 -0.4064)
			(end 0.7874 0.4064)
			(stroke
				(width 0.1524)
				(type default)
			)
			(layer "F.SilkS")
		)
		(fp_line
			(start 0.7874 0.4064)
			(end -0.7874 0.4064)
			(stroke
				(width 0.1524)
				(type default)
			)
			(layer "F.SilkS")
		)
		(fp_line
			(start -0.67945 -0.305054)
			(end -0.12065 -0.305054)
			(stroke
				(width 0.1)
				(type default)
			)
			(layer "F.Fab")
		)
		(fp_line
			(start -0.67945 0.3048)
			(end -0.67945 -0.305054)
			(stroke
				(width 0.1)
				(type default)
			)
			(layer "F.Fab")
		)
		(fp_line
			(start -0.12065 -0.305054)
			(end -0.12065 -0.2794)
			(stroke
				(width 0.1)
				(type default)
			)
			(layer "F.Fab")
		)
		(fp_line
			(start -0.12065 -0.2794)
			(end 0.12065 -0.2794)
			(stroke
				(width 0.1)
				(type default)
			)
			(layer "F.Fab")
		)
		(fp_line
			(start -0.12065 0.2794)
			(end -0.12065 0.3048)
			(stroke
				(width 0.1)
				(type default)
			)
			(layer "F.Fab")
		)
		(fp_line
			(start -0.12065 0.3048)
			(end -0.67945 0.3048)
			(stroke
				(width 0.1)
				(type default)
			)
			(layer "F.Fab")
		)
		(fp_line
			(start 0.120396 0.2794)
			(end -0.12065 0.2794)
			(stroke
				(width 0.1)
				(type default)
			)
			(layer "F.Fab")
		)
		(fp_line
			(start 0.120396 0.3048)
			(end 0.120396 0.2794)
			(stroke
				(width 0.1)
				(type default)
			)
			(layer "F.Fab")
		)
		(fp_line
			(start 0.12065 -0.3048)
			(end 0.67945 -0.3048)
			(stroke
				(width 0.1)
				(type default)
			)
			(layer "F.Fab")
		)
		(fp_line
			(start 0.12065 -0.2794)
			(end 0.12065 -0.3048)
			(stroke
				(width 0.1)
				(type default)
			)
			(layer "F.Fab")
		)
		(fp_line
			(start 0.67945 -0.3048)
			(end 0.67945 0.3048)
			(stroke
				(width 0.1)
				(type default)
			)
			(layer "F.Fab")
		)
		(fp_line
			(start 0.67945 0.3048)
			(end 0.120396 0.3048)
			(stroke
				(width 0.1)
				(type default)
			)
			(layer "F.Fab")
		)
		(pad "1" smd circle
			(at -0.40005 0)
			(size 0 0)
			(layers "F.Cu" "F.Mask" "F.Paste")
			(net "P3V3_AUX")
		)
		(pad "2" smd circle
			(at 0.40005 0)
			(size 0 0)
			(layers "F.Cu" "F.Mask" "F.Paste")
			(net "PRSNT_CABLE_SWB_B2_ISO_N")
		)
	)
	(footprint ""
		(layer "F.Cu")
		(at 28.021026 -428.755302)
		(property "Reference" "R6156"
			(at 0 0 0)
			(layer "F.SilkS")
			(hide yes)
			(effects
				(font
					(size 1.27 1.27)
				)
			)
		)
		(property "Value" ""
			(at 0 0 0)
			(layer "F.Fab")
			(effects
				(font
					(size 1.27 1.27)
				)
			)
		)
		(duplicate_pad_numbers_are_jumpers no)
		(fp_line
			(start -0.32512 -0.175006)
			(end 0.32512 -0.175006)
			(stroke
				(width 0.1)
				(type default)
			)
			(layer "F.Fab")
		)
		(fp_line
			(start -0.32512 0.175006)
			(end -0.32512 -0.175006)
			(stroke
				(width 0.1)
				(type default)
			)
			(layer "F.Fab")
		)
		(fp_line
			(start 0.32512 -0.175006)
			(end 0.32512 0.175006)
			(stroke
				(width 0.1)
				(type default)
			)
			(layer "F.Fab")
		)
		(fp_line
			(start 0.32512 0.175006)
			(end -0.32512 0.175006)
			(stroke
				(width 0.1)
				(type default)
			)
			(layer "F.Fab")
		)
		(pad "1" smd rect
			(at -0.2667 0)
			(size 0.3048 0.381)
			(layers "F.Cu" "F.Mask" "F.Paste")
			(net "P2E_MB_BMC_RX_DP<0>")
		)
		(pad "2" smd rect
			(at 0.2667 0 180)
			(size 0.3048 0.381)
			(layers "F.Cu" "F.Mask" "F.Paste")
			(net "P2E_MB_BMC_RX_R1_DP<0>")
		)
	)
	(footprint ""
		(layer "F.Cu")
		(at 335.114646 -403.603206 -90)
		(property "Reference" "R1037"
			(at 0 0 270)
			(layer "F.SilkS")
			(hide yes)
			(effects
				(font
					(size 1.27 1.27)
				)
			)
		)
		(property "Value" ""
			(at 0 0 270)
			(layer "F.Fab")
			(effects
				(font
					(size 1.27 1.27)
				)
			)
		)
		(duplicate_pad_numbers_are_jumpers no)
		(fp_line
			(start -0.32512 0.175006)
			(end -0.32512 -0.175006)
			(stroke
				(width 0.1)
				(type default)
			)
			(layer "F.Fab")
		)
		(fp_line
			(start 0.32512 0.175006)
			(end -0.32512 0.175006)
			(stroke
				(width 0.1)
				(type default)
			)
			(layer "F.Fab")
		)
		(fp_line
			(start -0.32512 -0.175006)
			(end 0.32512 -0.175006)
			(stroke
				(width 0.1)
				(type default)
			)
			(layer "F.Fab")
		)
		(fp_line
			(start 0.32512 -0.175006)
			(end 0.32512 0.175006)
			(stroke
				(width 0.1)
				(type default)
			)
			(layer "F.Fab")
		)
		(pad "1" smd rect
			(at -0.2667 0 270)
			(size 0.3048 0.381)
			(layers "F.Cu" "F.Mask" "F.Paste")
			(net "JTAG_TEST_MODE_RT_CPU0_P1")
		)
		(pad "2" smd rect
			(at 0.2667 0 90)
			(size 0.3048 0.381)
			(layers "F.Cu" "F.Mask" "F.Paste")
			(net "GND")
		)
	)
	(footprint ""
		(layer "F.Cu")
		(at 191.065404 -32.110426 180)
		(property "Reference" "PD115"
			(at 2.149348 1.672336 0)
			(unlocked yes)
			(layer "F.SilkS")
			(effects
				(font
					(size 0.7874 0.5842)
					(thickness 0.1524)
				)
				(justify left)
			)
		)
		(property "Value" ""
			(at 0 0 180)
			(layer "F.Fab")
			(effects
				(font
					(size 1.27 1.27)
				)
			)
		)
		(duplicate_pad_numbers_are_jumpers no)
		(fp_line
			(start 2.631186 0.999998)
			(end 2.631186 -0.999998)
			(stroke
				(width 0.1524)
				(type default)
			)
			(layer "F.SilkS")
		)
		(fp_line
			(start 2.631186 -0.999998)
			(end -2.250186 -0.999998)
			(stroke
				(width 0.1524)
				(type default)
			)
			(layer "F.SilkS")
		)
		(fp_line
			(start 0.381 -0.0508)
			(end 0.635 -0.0508)
			(stroke
				(width 0.1524)
				(type default)
			)
			(layer "F.SilkS")
		)
		(fp_line
			(start 0.381 -0.0508)
			(end -0.381 0.3302)
			(stroke
				(width 0.1524)
				(type default)
			)
			(layer "F.SilkS")
		)
		(fp_line
			(start 0.381 -0.4318)
			(end 0.381 0.3302)
			(stroke
				(width 0.1524)
				(type default)
			)
			(layer "F.SilkS")
		)
		(fp_line
			(start -0.381 0.3302)
			(end -0.381 -0.4318)
			(stroke
				(width 0.1524)
				(type default)
			)
			(layer "F.SilkS")
		)
		(fp_line
			(start -0.381 -0.0508)
			(end -0.6604 -0.0508)
			(stroke
				(width 0.1524)
				(type default)
			)
			(layer "F.SilkS")
		)
		(fp_line
			(start -0.381 -0.4318)
			(end 0.381 -0.0508)
			(stroke
				(width 0.1524)
				(type default)
			)
			(layer "F.SilkS")
		)
		(fp_line
			(start -2.250186 0.999998)
			(end 2.631186 0.999998)
			(stroke
				(width 0.1524)
				(type default)
			)
			(layer "F.SilkS")
		)
		(fp_line
			(start -2.250186 -0.999998)
			(end -2.250186 0.999998)
			(stroke
				(width 0.1524)
				(type default)
			)
			(layer "F.SilkS")
		)
		(fp_rect
			(start 2.6162 -0.9652)
			(end 2.1844 1.016)
			(stroke
				(width 0)
				(type default)
			)
			(fill yes)
			(layer "F.SilkS")
		)
		(fp_line
			(start 1.450086 0.999998)
			(end 1.450086 -0.999998)
			(stroke
				(width 0.1)
				(type default)
			)
			(layer "F.Fab")
		)
		(fp_line
			(start 1.450086 -0.999998)
			(end -1.450086 -0.999998)
			(stroke
				(width 0.1)
				(type default)
			)
			(layer "F.Fab")
		)
		(fp_line
			(start -1.450086 0.999998)
			(end 1.450086 0.999998)
			(stroke
				(width 0.1)
				(type default)
			)
			(layer "F.Fab")
		)
		(fp_line
			(start -1.450086 -0.999998)
			(end -1.450086 0.999998)
			(stroke
				(width 0.1)
				(type default)
			)
			(layer "F.Fab")
		)
		(fp_text user "-"
			(at 2.4384 -0.22225 180)
			(unlocked yes)
			(layer "F.SilkS")
			(effects
				(font
					(size 1.905 1.4224)
					(thickness 0.1524)
				)
				(justify left)
			)
		)
		(fp_text user "+"
			(at -3.4798 -0.22225 180)
			(unlocked yes)
			(layer "F.SilkS")
			(effects
				(font
					(size 1.905 1.4224)
					(thickness 0.1524)
				)
				(justify left)
			)
		)
		(fp_text user "-"
			(at 2.4384 -0.22225 180)
			(unlocked yes)
			(layer "F.Fab")
			(effects
				(font
					(size 1.905 1.4224)
					(thickness 0.1524)
				)
				(justify left)
			)
		)
		(fp_text user "+"
			(at -3.4798 -0.22225 180)
			(unlocked yes)
			(layer "F.Fab")
			(effects
				(font
					(size 1.905 1.4224)
					(thickness 0.1524)
				)
				(justify left)
			)
		)
		(pad "A" smd rect
			(at -1.450086 0 180)
			(size 1.3208 1.4224)
			(layers "F.Cu" "F.Mask" "F.Paste")
			(net "GND")
		)
		(pad "C" smd rect
			(at 1.450086 0 180)
			(size 1.3208 1.4224)
			(layers "F.Cu" "F.Mask" "F.Paste")
			(net "P12V_AUX")
		)
	)
	(footprint ""
		(layer "F.Cu")
		(at 461.460088 -347.699838)
		(property "Reference" "H95"
			(at -5.244084 -5.691886 0)
			(unlocked yes)
			(layer "F.SilkS")
			(effects
				(font
					(size 0.7874 0.5842)
					(thickness 0.1524)
				)
				(justify left)
			)
		)
		(property "Value" ""
			(at 0 0 0)
			(layer "F.Fab")
			(effects
				(font
					(size 1.27 1.27)
				)
			)
		)
		(duplicate_pad_numbers_are_jumpers no)
		(pad "1" thru_hole circle
			(at 0 0)
			(size 10.0076 10.0076)
			(drill 5.6134)
			(layers "*.Cu" "*.Mask")
			(remove_unused_layers no)
			(net "GND")
			(clearance -1.9431)
		)
	)
)
